# SCM (Grand Teton) — schematic netlist excerpt (pin names and nets, part order shuffled) for the footprints in the layout excerpt that follows; sources: Cadence DE-HDL packaged netlist, KiCad conversion of 12092022_DA0F0TMDCD0_F0T_Management_Board_D_brd_V3_OCP.brd

R493  Q_RES  150K 1% EMPTY  pkg 0402LF  page 17 : A = LPC_ESPI_SEL_N ; B = GND
R349  Q_RES  120 1% CHIP  pkg 0402LF  page 20 : A = GND ; B = M_BMC_DDR4_MCKE

(kicad_pcb
	(version 20260206)
	(generator "pcbnew")
	(generator_version "10.0")
	(general
		(thickness 1.6)
		(legacy_teardrops no)
	)
	(paper "A4")
	(title_block
		(title "12092022_DA0F0TMDCD0_F0T_Management_Board_D_brd_V3_OCP.brd")
		(comment 1 "Grand Teton / footprints 1398-1399 of 1440")
	)
	(layers
		(0 "F.Cu" signal "TOP")
		(4 "In1.Cu" signal "GND")
		(6 "In2.Cu" signal "IN1")
		(8 "In3.Cu" signal "GND1")
		(10 "In4.Cu" signal "IN2")
		(12 "In5.Cu" signal "VCC")
		(14 "In6.Cu" signal "VCC1")
		(16 "In7.Cu" signal "IN3")
		(18 "In8.Cu" signal "GND2")
		(20 "In9.Cu" signal "IN4")
		(22 "In10.Cu" signal "GND3")
		(2 "B.Cu" signal "BOTTOM")
		(9 "F.Adhes" user "F.Adhesive")
		(11 "B.Adhes" user "B.Adhesive")
		(13 "F.Paste" user "Package Geometry/Pastemask Top")
		(15 "B.Paste" user "Package Geometry/Pastemask Bottom")
		(5 "F.SilkS" user "Ref Des/Silkscreen Top")
		(7 "B.SilkS" user "Ref Des/Silkscreen Bottom")
		(1 "F.Mask" user "Board Geometry/Soldermask Top")
		(3 "B.Mask" user "Board Geometry/Soldermask Bottom")
		(17 "Dwgs.User" user "User.Drawings")
		(19 "Cmts.User" user "User.Comments")
		(21 "Eco1.User" user "User.Eco1")
		(23 "Eco2.User" user "User.Eco2")
		(25 "Edge.Cuts" user "Board Geometry/Outline")
		(27 "Margin" user)
		(31 "F.CrtYd" user "Package Geometry/Place Bound Top")
		(29 "B.CrtYd" user "Package Geometry/Place Bound Bottom")
		(35 "F.Fab" user "Ref Des/Assembly Top")
		(33 "B.Fab" user "Ref Des/Assembly Bottom")
	)
	(footprint ""
		(layer "B.Cu")
		(at 70.832472 -47.106332 90)
		(property "Reference" "R349"
			(at 0 0 90)
			(layer "B.SilkS")
			(hide yes)
			(effects
				(font
					(size 1.27 1.27)
				)
				(justify mirror)
			)
		)
		(property "Value" ""
			(at 0 0 90)
			(layer "B.Fab")
			(effects
				(font
					(size 1.27 1.27)
				)
				(justify mirror)
			)
		)
		(duplicate_pad_numbers_are_jumpers no)
		(fp_line
			(start 0.7874 -0.4064)
			(end -0.7874 -0.4064)
			(stroke
				(width 0.1524)
				(type default)
			)
			(layer "B.SilkS")
		)
		(fp_line
			(start -0.7874 -0.4064)
			(end -0.7874 0.4064)
			(stroke
				(width 0.1524)
				(type default)
			)
			(layer "B.SilkS")
		)
		(fp_line
			(start 0.7874 0.4064)
			(end 0.7874 -0.4064)
			(stroke
				(width 0.1524)
				(type default)
			)
			(layer "B.SilkS")
		)
		(fp_line
			(start -0.7874 0.4064)
			(end 0.7874 0.4064)
			(stroke
				(width 0.1524)
				(type default)
			)
			(layer "B.SilkS")
		)
		(fp_line
			(start 0.67945 -0.305054)
			(end 0.12065 -0.305054)
			(stroke
				(width 0.1)
				(type default)
			)
			(layer "B.Fab")
		)
		(fp_line
			(start 0.12065 -0.305054)
			(end 0.12065 -0.2794)
			(stroke
				(width 0.1)
				(type default)
			)
			(layer "B.Fab")
		)
		(fp_line
			(start -0.12065 -0.3048)
			(end -0.67945 -0.3048)
			(stroke
				(width 0.1)
				(type default)
			)
			(layer "B.Fab")
		)
		(fp_line
			(start -0.67945 -0.3048)
			(end -0.67945 0.3048)
			(stroke
				(width 0.1)
				(type default)
			)
			(layer "B.Fab")
		)
		(fp_line
			(start 0.12065 -0.2794)
			(end -0.12065 -0.2794)
			(stroke
				(width 0.1)
				(type default)
			)
			(layer "B.Fab")
		)
		(fp_line
			(start -0.12065 -0.2794)
			(end -0.12065 -0.3048)
			(stroke
				(width 0.1)
				(type default)
			)
			(layer "B.Fab")
		)
		(fp_line
			(start 0.12065 0.2794)
			(end 0.12065 0.3048)
			(stroke
				(width 0.1)
				(type default)
			)
			(layer "B.Fab")
		)
		(fp_line
			(start -0.120396 0.2794)
			(end 0.12065 0.2794)
			(stroke
				(width 0.1)
				(type default)
			)
			(layer "B.Fab")
		)
		(fp_line
			(start 0.67945 0.3048)
			(end 0.67945 -0.305054)
			(stroke
				(width 0.1)
				(type default)
			)
			(layer "B.Fab")
		)
		(fp_line
			(start 0.12065 0.3048)
			(end 0.67945 0.3048)
			(stroke
				(width 0.1)
				(type default)
			)
			(layer "B.Fab")
		)
		(fp_line
			(start -0.120396 0.3048)
			(end -0.120396 0.2794)
			(stroke
				(width 0.1)
				(type default)
			)
			(layer "B.Fab")
		)
		(fp_line
			(start -0.67945 0.3048)
			(end -0.120396 0.3048)
			(stroke
				(width 0.1)
				(type default)
			)
			(layer "B.Fab")
		)
		(pad "1" smd circle
			(at 0.40005 0 270)
			(size 0 0)
			(layers "B.Cu" "B.Mask" "B.Paste")
			(net "GND")
		)
		(pad "2" smd circle
			(at -0.40005 0 270)
			(size 0 0)
			(layers "B.Cu" "B.Mask" "B.Paste")
			(net "M_BMC_DDR4_MCKE")
		)
	)
	(footprint ""
		(layer "B.Cu")
		(at 68.2752 -97.5614 180)
		(property "Reference" "R493"
			(at 0 0 0)
			(layer "B.SilkS")
			(hide yes)
			(effects
				(font
					(size 1.27 1.27)
				)
				(justify mirror)
			)
		)
		(property "Value" ""
			(at 0 0 0)
			(layer "B.Fab")
			(effects
				(font
					(size 1.27 1.27)
				)
				(justify mirror)
			)
		)
		(duplicate_pad_numbers_are_jumpers no)
		(fp_line
			(start 0.7874 0.4064)
			(end 0.7874 -0.4064)
			(stroke
				(width 0.1524)
				(type default)
			)
			(layer "B.SilkS")
		)
		(fp_line
			(start 0.7874 -0.4064)
			(end -0.7874 -0.4064)
			(stroke
				(width 0.1524)
				(type default)
			)
			(layer "B.SilkS")
		)
		(fp_line
			(start -0.7874 0.4064)
			(end 0.7874 0.4064)
			(stroke
				(width 0.1524)
				(type default)
			)
			(layer "B.SilkS")
		)
		(fp_line
			(start -0.7874 -0.4064)
			(end -0.7874 0.4064)
			(stroke
				(width 0.1524)
				(type default)
			)
			(layer "B.SilkS")
		)
		(fp_line
			(start 0.67945 0.3048)
			(end 0.67945 -0.305054)
			(stroke
				(width 0.1)
				(type default)
			)
			(layer "B.Fab")
		)
		(fp_line
			(start 0.67945 -0.305054)
			(end 0.12065 -0.305054)
			(stroke
				(width 0.1)
				(type default)
			)
			(layer "B.Fab")
		)
		(fp_line
			(start 0.12065 0.3048)
			(end 0.67945 0.3048)
			(stroke
				(width 0.1)
				(type default)
			)
			(layer "B.Fab")
		)
		(fp_line
			(start 0.12065 0.2794)
			(end 0.12065 0.3048)
			(stroke
				(width 0.1)
				(type default)
			)
			(layer "B.Fab")
		)
		(fp_line
			(start 0.12065 -0.2794)
			(end -0.12065 -0.2794)
			(stroke
				(width 0.1)
				(type default)
			)
			(layer "B.Fab")
		)
		(fp_line
			(start 0.12065 -0.305054)
			(end 0.12065 -0.2794)
			(stroke
				(width 0.1)
				(type default)
			)
			(layer "B.Fab")
		)
		(fp_line
			(start -0.120396 0.3048)
			(end -0.120396 0.2794)
			(stroke
				(width 0.1)
				(type default)
			)
			(layer "B.Fab")
		)
		(fp_line
			(start -0.120396 0.2794)
			(end 0.12065 0.2794)
			(stroke
				(width 0.1)
				(type default)
			)
			(layer "B.Fab")
		)
		(fp_line
			(start -0.12065 -0.2794)
			(end -0.12065 -0.3048)
			(stroke
				(width 0.1)
				(type default)
			)
			(layer "B.Fab")
		)
		(fp_line
			(start -0.12065 -0.3048)
			(end -0.67945 -0.3048)
			(stroke
				(width 0.1)
				(type default)
			)
			(layer "B.Fab")
		)
		(fp_line
			(start -0.67945 0.3048)
			(end -0.120396 0.3048)
			(stroke
				(width 0.1)
				(type default)
			)
			(layer "B.Fab")
		)
		(fp_line
			(start -0.67945 -0.3048)
			(end -0.67945 0.3048)
			(stroke
				(width 0.1)
				(type default)
			)
			(layer "B.Fab")
		)
		(pad "1" smd circle
			(at 0.40005 0)
			(size 0 0)
			(layers "B.Cu" "B.Mask" "B.Paste")
			(net "LPC_ESPI_SEL_N")
		)
		(pad "2" smd circle
			(at -0.40005 0)
			(size 0 0)
			(layers "B.Cu" "B.Mask" "B.Paste")
			(net "GND")
		)
	)
)
